# BASEBOARD_FAB2 (Tioga Pass) — schematic netlist excerpt (pin names and nets, part order shuffled) for the footprints in the layout excerpt that follows; sources: Cadence DE-HDL packaged netlist, KiCad conversion of Wiwynn_Tioga_Pass_MB.brd

C5G9  CAP  100UF 4V 20% X5R  pkg 0805  page 217 : A = PVDDQ_ABC ; B = GND
C30W4  SC22U16V5MX-4-GP  20%  pkg SMD-BCG5  page 253 : \1\ = P5V_STBY_USBC ; \2\ = GND
R7B4  RES  1.00K 1% CHIP  pkg 0402  page 218 : A = P3V3_STBY ; B = IRQ_PVDDQ_DEF_VRHOT_LVT3_R_N

(kicad_pcb
	(version 20260206)
	(generator "pcbnew")
	(generator_version "10.0")
	(general
		(thickness 1.6)
		(legacy_teardrops no)
	)
	(paper "A4")
	(title_block
		(title "Wiwynn_Tioga_Pass_MB.brd")
		(comment 1 "Tioga Pass / footprints 649-651 of 4770")
	)
	(layers
		(0 "F.Cu" signal "TOP")
		(4 "In1.Cu" signal "L2GND")
		(6 "In2.Cu" signal "L3")
		(8 "In3.Cu" signal "L4GND")
		(10 "In4.Cu" signal "L5")
		(12 "In5.Cu" signal "L6GND")
		(14 "In6.Cu" signal "L7VCC")
		(16 "In7.Cu" signal "L8VCC")
		(18 "In8.Cu" signal "L9GND")
		(20 "In9.Cu" signal "L10")
		(22 "In10.Cu" signal "L11GND")
		(24 "In11.Cu" signal "L12")
		(26 "In12.Cu" signal "L13GND")
		(2 "B.Cu" signal "BOTTOM")
		(9 "F.Adhes" user "F.Adhesive")
		(11 "B.Adhes" user "B.Adhesive")
		(13 "F.Paste" user "Package Geometry/Pastemask Top")
		(15 "B.Paste" user "Package Geometry/Pastemask Bottom")
		(5 "F.SilkS" user "Ref Des/Silkscreen Top")
		(7 "B.SilkS" user "Ref Des/Silkscreen Bottom")
		(1 "F.Mask" user "Board Geometry/Soldermask Top")
		(3 "B.Mask" user "Board Geometry/Soldermask Bottom")
		(17 "Dwgs.User" user "User.Drawings")
		(19 "Cmts.User" user "User.Comments")
		(21 "Eco1.User" user "User.Eco1")
		(23 "Eco2.User" user "User.Eco2")
		(25 "Edge.Cuts" user "Board Geometry/Outline")
		(27 "Margin" user)
		(31 "F.CrtYd" user "Package Geometry/Place Bound Top")
		(29 "B.CrtYd" user "Package Geometry/Place Bound Bottom")
		(35 "F.Fab" user "Ref Des/Assembly Top")
		(33 "B.Fab" user "Ref Des/Assembly Bottom")
	)
	(footprint ""
		(layer "F.Cu")
		(at 362.9152 -133.096 180)
		(property "Reference" "R7B4"
			(at 0 0 180)
			(layer "F.SilkS")
			(hide yes)
			(effects
				(font
					(size 1.27 1.27)
				)
			)
		)
		(property "Value" ""
			(at 0 0 180)
			(layer "F.Fab")
			(effects
				(font
					(size 1.27 1.27)
				)
			)
		)
		(duplicate_pad_numbers_are_jumpers no)
		(fp_poly
			(pts
				(xy -0.2794 -0.1016) (xy 0.2794 -0.1016) (xy 0.2794 0.9906) (xy -0.2794 0.9906)
			)
			(stroke
				(width 0)
				(type default)
			)
			(fill no)
			(layer "F.CrtYd")
		)
		(fp_line
			(start 0.2794 0.9906)
			(end 0.2794 -0.1016)
			(stroke
				(width 0.1)
				(type default)
			)
			(layer "F.Fab")
		)
		(fp_line
			(start 0.2794 -0.1016)
			(end -0.2794 -0.1016)
			(stroke
				(width 0.1)
				(type default)
			)
			(layer "F.Fab")
		)
		(fp_line
			(start -0.2794 0.9906)
			(end 0.2794 0.9906)
			(stroke
				(width 0.1)
				(type default)
			)
			(layer "F.Fab")
		)
		(fp_line
			(start -0.2794 -0.1016)
			(end -0.2794 0.9906)
			(stroke
				(width 0.1)
				(type default)
			)
			(layer "F.Fab")
		)
		(pad "1" smd rect
			(at 0 0 180)
			(size 0.508 0.508)
			(layers "F.Cu" "F.Mask" "F.Paste")
			(net "P3V3_STBY")
		)
		(pad "2" smd rect
			(at 0 0.889 180)
			(size 0.508 0.508)
			(layers "F.Cu" "F.Mask" "F.Paste")
			(net "IRQ_PVDDQ_DEF_VRHOT_LVT3_R_N")
		)
		(zone
			(layer "F.Cu")
			(hatch none 0.5)
			(connect_pads
				(clearance 0)
			)
			(min_thickness 0.25)
			(keepout
				(tracks not_allowed)
				(vias allowed)
				(pads allowed)
				(copperpour not_allowed)
				(footprints allowed)
			)
			(placement
				(enabled no)
				(sheetname "")
			)
			(fill
				(thermal_gap 0.5)
				(thermal_bridge_width 0.5)
				(island_removal_mode 0)
			)
			(polygon
				(pts
					(xy 363.1692 -133.731) (xy 362.6612 -133.731) (xy 362.6612 -133.35) (xy 363.1692 -133.35)
				)
			)
		)
		(zone
			(layer "F.Cu")
			(hatch none 0.5)
			(connect_pads
				(clearance 0)
			)
			(min_thickness 0.25)
			(keepout
				(tracks allowed)
				(vias not_allowed)
				(pads allowed)
				(copperpour not_allowed)
				(footprints allowed)
			)
			(placement
				(enabled no)
				(sheetname "")
			)
			(fill
				(thermal_gap 0.5)
				(thermal_bridge_width 0.5)
				(island_removal_mode 0)
			)
			(polygon
				(pts
					(xy 363.1692 -133.35) (xy 362.6612 -133.35) (xy 362.6612 -133.731) (xy 363.1692 -133.731)
				)
			)
		)
	)
	(footprint ""
		(layer "F.Cu")
		(at 490.148372 -55.87365)
		(property "Reference" "C30W4"
			(at 0 0 0)
			(layer "F.SilkS")
			(hide yes)
			(effects
				(font
					(size 1.27 1.27)
				)
			)
		)
		(property "Value" "*"
			(at -0.0762 -6.2357 0)
			(unlocked yes)
			(layer "F.Fab")
			(hide yes)
			(effects
				(font
					(size 1.27 1.016)
					(thickness 0.1524)
				)
			)
		)
		(property "Device Type" "SC22U16V5MX-4-GP_SMD-BCG5-SC22A"
			(at -0.0762 -8.2677 0)
			(unlocked yes)
			(layer "F.Fab")
			(hide yes)
			(effects
				(font
					(size 1.27 1.016)
					(thickness 0.1524)
				)
			)
		)
		(duplicate_pad_numbers_are_jumpers no)
		(fp_line
			(start 0.635 0)
			(end -0.635 0)
			(stroke
				(width 0.508)
				(type default)
			)
			(layer "F.SilkS")
		)
		(fp_rect
			(start -0.9652 1.778)
			(end 0.9652 -1.778)
			(stroke
				(width 0)
				(type default)
			)
			(fill no)
			(layer "F.CrtYd")
		)
		(fp_poly
			(pts
				(xy -0.9652 -1.778) (xy 0.9652 -1.778) (xy 0.9652 1.778) (xy -0.9652 1.778)
			)
			(stroke
				(width 0)
				(type default)
			)
			(fill no)
			(layer "F.Fab")
		)
		(pad "1" smd rect
			(at 0 -0.9652)
			(size 1.397 1.143)
			(layers "F.Cu" "F.Mask" "F.Paste")
			(net "P5V_STBY_USBC")
		)
		(pad "2" smd rect
			(at 0 0.9652)
			(size 1.397 1.143)
			(layers "F.Cu" "F.Mask" "F.Paste")
			(net "GND")
		)
	)
	(footprint ""
		(layer "F.Cu")
		(at 259.49402 -12.961112 90)
		(property "Reference" "C5G9"
			(at 0 0 90)
			(layer "F.SilkS")
			(hide yes)
			(effects
				(font
					(size 1.27 1.27)
				)
			)
		)
		(property "Value" ""
			(at 0 0 90)
			(layer "F.Fab")
			(effects
				(font
					(size 1.27 1.27)
				)
			)
		)
		(duplicate_pad_numbers_are_jumpers no)
		(fp_rect
			(start -0.7239 -0.2159)
			(end 0.7239 1.9939)
			(stroke
				(width 0)
				(type default)
			)
			(fill no)
			(layer "F.CrtYd")
		)
		(fp_line
			(start 0.7239 -0.2159)
			(end -0.7239 -0.2159)
			(stroke
				(width 0.1)
				(type default)
			)
			(layer "F.Fab")
		)
		(fp_line
			(start -0.7239 -0.2159)
			(end -0.7239 1.9939)
			(stroke
				(width 0.1)
				(type default)
			)
			(layer "F.Fab")
		)
		(fp_line
			(start 0.7239 1.9939)
			(end 0.7239 -0.2159)
			(stroke
				(width 0.1)
				(type default)
			)
			(layer "F.Fab")
		)
		(fp_line
			(start -0.7239 1.9939)
			(end 0.7239 1.9939)
			(stroke
				(width 0.1)
				(type default)
			)
			(layer "F.Fab")
		)
		(pad "1" smd rect
			(at 0 0 90)
			(size 1.27 1.016)
			(layers "F.Cu" "F.Mask" "F.Paste")
			(net "PVDDQ_ABC")
		)
		(pad "2" smd rect
			(at 0 1.778 90)
			(size 1.27 1.016)
			(layers "F.Cu" "F.Mask" "F.Paste")
			(net "GND")
		)
		(zone
			(layer "F.Cu")
			(hatch none 0.5)
			(connect_pads
				(clearance 0)
			)
			(min_thickness 0.25)
			(keepout
				(tracks not_allowed)
				(vias allowed)
				(pads allowed)
				(copperpour not_allowed)
				(footprints allowed)
			)
			(placement
				(enabled no)
				(sheetname "")
			)
			(fill
				(thermal_gap 0.5)
				(thermal_bridge_width 0.5)
				(island_removal_mode 0)
			)
			(polygon
				(pts
					(xy 260.00202 -12.326112) (xy 260.76402 -12.326112) (xy 260.76402 -13.596112) (xy 260.00202 -13.596112)
				)
			)
		)
	)
)
